# BASEBOARD_FAB2 (Tioga Pass) — schematic netlist excerpt (pin names and nets, part order shuffled) for the footprints in the layout excerpt that follows; sources: Cadence DE-HDL packaged netlist, KiCad conversion of Wiwynn_Tioga_Pass_MB.brd

C6B9  CAP  0.22UF 16V 10% X7R  pkg 0402  page 105 : A = P3E_CPU0_PE1_PCH_TXN<13> ; B = P3E_CPU0_PE1_PCH_C_TXN<13>

RM1E1  CONN3_G98259001  CONN  pkg PIP  page 195
  IO1  = GND
  IO2  = GND
  IO3  = GND

(kicad_pcb
	(version 20260206)
	(generator "pcbnew")
	(generator_version "10.0")
	(general
		(thickness 1.6)
		(legacy_teardrops no)
	)
	(paper "A4")
	(title_block
		(title "Wiwynn_Tioga_Pass_MB.brd")
		(comment 1 "Tioga Pass / footprints 2181-2182 of 4770")
	)
	(layers
		(0 "F.Cu" signal "TOP")
		(4 "In1.Cu" signal "L2GND")
		(6 "In2.Cu" signal "L3")
		(8 "In3.Cu" signal "L4GND")
		(10 "In4.Cu" signal "L5")
		(12 "In5.Cu" signal "L6GND")
		(14 "In6.Cu" signal "L7VCC")
		(16 "In7.Cu" signal "L8VCC")
		(18 "In8.Cu" signal "L9GND")
		(20 "In9.Cu" signal "L10")
		(22 "In10.Cu" signal "L11GND")
		(24 "In11.Cu" signal "L12")
		(26 "In12.Cu" signal "L13GND")
		(2 "B.Cu" signal "BOTTOM")
		(9 "F.Adhes" user "F.Adhesive")
		(11 "B.Adhes" user "B.Adhesive")
		(13 "F.Paste" user "Package Geometry/Pastemask Top")
		(15 "B.Paste" user "Package Geometry/Pastemask Bottom")
		(5 "F.SilkS" user "Ref Des/Silkscreen Top")
		(7 "B.SilkS" user "Ref Des/Silkscreen Bottom")
		(1 "F.Mask" user "Board Geometry/Soldermask Top")
		(3 "B.Mask" user "Board Geometry/Soldermask Bottom")
		(17 "Dwgs.User" user "User.Drawings")
		(19 "Cmts.User" user "User.Comments")
		(21 "Eco1.User" user "User.Eco1")
		(23 "Eco2.User" user "User.Eco2")
		(25 "Edge.Cuts" user "Board Geometry/Outline")
		(27 "Margin" user)
		(31 "F.CrtYd" user "Package Geometry/Place Bound Top")
		(29 "B.CrtYd" user "Package Geometry/Place Bound Bottom")
		(35 "F.Fab" user "Ref Des/Assembly Top")
		(33 "B.Fab" user "Ref Des/Assembly Bottom")
	)
	(footprint ""
		(layer "F.Cu")
		(at 11.249914 -45.310044 -90)
		(property "Reference" "RM1E1"
			(at 1.495044 -4.651756 90)
			(unlocked yes)
			(layer "F.SilkS")
			(effects
				(font
					(size 0.7874 0.5842)
					(thickness 0.1524)
				)
				(justify left)
			)
		)
		(property "Value" ""
			(at 0 0 270)
			(layer "F.Fab")
			(effects
				(font
					(size 1.27 1.27)
				)
			)
		)
		(duplicate_pad_numbers_are_jumpers no)
		(fp_line
			(start -3.549904 17.223994)
			(end -3.549904 -3.929888)
			(stroke
				(width 0.1524)
				(type default)
			)
			(layer "F.SilkS")
		)
		(fp_line
			(start -3.549904 -3.929888)
			(end 3.549904 -3.929888)
			(stroke
				(width 0.1524)
				(type default)
			)
			(layer "F.SilkS")
		)
		(fp_line
			(start 3.549904 -3.929888)
			(end 3.549904 17.202912)
			(stroke
				(width 0.1524)
				(type default)
			)
			(layer "F.SilkS")
		)
		(fp_poly
			(pts
				(xy 4.863084 -2.237486) (xy 3.593084 -2.745486) (xy 4.863084 -3.253486)
			)
			(stroke
				(width 0)
				(type default)
			)
			(fill yes)
			(layer "F.SilkS")
		)
		(fp_poly
			(pts
				(xy 5.80644 0.05715) (xy 4.53644 -0.45085) (xy 5.80644 -0.95885)
			)
			(stroke
				(width 0)
				(type default)
			)
			(fill yes)
			(layer "B.SilkS")
		)
		(fp_poly
			(pts
				(xy -3.549904 -3.929888) (xy 3.549904 -3.929888) (xy 3.549904 20.7899) (xy 1.599946 20.7899) (xy 1.599946 42.489882)
				(xy -1.599946 42.489882) (xy -1.599946 20.7899) (xy -3.549904 20.7899)
			)
			(stroke
				(width 0)
				(type default)
			)
			(fill no)
			(layer "F.CrtYd")
		)
		(fp_poly
			(pts
				(xy 6.134608 0.049022) (xy 4.864608 -0.458978) (xy 6.134608 -0.966978)
			)
			(stroke
				(width 0)
				(type default)
			)
			(fill yes)
			(layer "B.Fab")
		)
		(fp_line
			(start -1.599946 42.489882)
			(end -1.599946 20.7899)
			(stroke
				(width 0.1)
				(type default)
			)
			(layer "F.Fab")
		)
		(fp_line
			(start 1.599946 42.489882)
			(end -1.599946 42.489882)
			(stroke
				(width 0.1)
				(type default)
			)
			(layer "F.Fab")
		)
		(fp_line
			(start -3.549904 20.7899)
			(end -3.549904 -3.929888)
			(stroke
				(width 0.1)
				(type default)
			)
			(layer "F.Fab")
		)
		(fp_line
			(start -1.599946 20.7899)
			(end -3.549904 20.7899)
			(stroke
				(width 0.1)
				(type default)
			)
			(layer "F.Fab")
		)
		(fp_line
			(start 1.599946 20.7899)
			(end 1.599946 42.489882)
			(stroke
				(width 0.1)
				(type default)
			)
			(layer "F.Fab")
		)
		(fp_line
			(start 3.549904 20.7899)
			(end 1.599946 20.7899)
			(stroke
				(width 0.1)
				(type default)
			)
			(layer "F.Fab")
		)
		(fp_line
			(start -3.549904 -3.929888)
			(end 3.549904 -3.929888)
			(stroke
				(width 0.1)
				(type default)
			)
			(layer "F.Fab")
		)
		(fp_line
			(start 3.549904 -3.929888)
			(end 3.549904 20.7899)
			(stroke
				(width 0.1)
				(type default)
			)
			(layer "F.Fab")
		)
		(fp_poly
			(pts
				(xy 6.134608 0.051054) (xy 4.864608 -0.456946) (xy 6.134608 -0.964946)
			)
			(stroke
				(width 0)
				(type default)
			)
			(fill yes)
			(layer "F.Fab")
		)
		(fp_text user "2"
			(at -4.34721 -1.956308 0)
			(unlocked yes)
			(layer "F.SilkS")
			(effects
				(font
					(size 0.7874 0.5842)
					(thickness 0.1524)
				)
				(justify left)
			)
		)
		(fp_text user "3"
			(at -4.120642 -3.068066 0)
			(unlocked yes)
			(layer "F.SilkS")
			(effects
				(font
					(size 0.7874 0.5842)
					(thickness 0.1524)
				)
				(justify left)
			)
		)
		(fp_text user "2"
			(at 2.892044 11.624564 270)
			(unlocked yes)
			(layer "B.Fab")
			(effects
				(font
					(size 0.635 0.635)
					(thickness 0.1524)
				)
				(justify left mirror)
			)
		)
		(fp_text user "3"
			(at -2.518156 6.747764 270)
			(unlocked yes)
			(layer "B.Fab")
			(effects
				(font
					(size 0.635 0.635)
					(thickness 0.1524)
				)
				(justify left mirror)
			)
		)
		(fp_text user "2"
			(at 2.257044 11.624564 270)
			(unlocked yes)
			(layer "F.Fab")
			(effects
				(font
					(size 0.635 0.635)
					(thickness 0.1524)
				)
				(justify left)
			)
		)
		(fp_text user "3"
			(at -2.848356 6.722364 270)
			(unlocked yes)
			(layer "F.Fab")
			(effects
				(font
					(size 0.635 0.635)
					(thickness 0.1524)
				)
				(justify left)
			)
		)
		(pad "1" thru_hole rect
			(at 0 0 270)
			(size 3.556 3.556)
			(drill 3.175)
			(layers "*.Cu" "*.Mask")
			(remove_unused_layers no)
			(net "GND")
			(clearance 0.127)
			(thermal_gap 0.127)
			(padstack
				(mode front_inner_back)
				(layer "Inner"
					(shape circle)
					(size 3.556 3.556)
					(clearance 0.127)
				)
				(layer "B.Cu"
					(shape rect)
					(size 3.556 3.556)
					(clearance 0.127)
				)
			)
		)
		(pad "2" thru_hole circle
			(at 0 11.75004 270)
			(size 3.556 3.556)
			(drill 3.175)
			(layers "*.Cu" "*.Mask")
			(remove_unused_layers no)
			(net "GND")
			(clearance 0.127)
			(thermal_gap 0.127)
		)
		(pad "3" thru_hole circle
			(at 0 6.620002 270)
			(size 3.556 3.556)
			(drill 3.175)
			(layers "*.Cu" "*.Mask")
			(remove_unused_layers no)
			(net "GND")
			(clearance 0.127)
			(thermal_gap 0.127)
		)
	)
	(footprint ""
		(layer "F.Cu")
		(at 324.5485 -121.666 90)
		(property "Reference" "C6B9"
			(at -0.8382 -0.67818 90)
			(unlocked yes)
			(layer "F.SilkS")
			(effects
				(font
					(size 0.4064 0.254)
					(thickness 0.1524)
				)
				(justify left)
			)
		)
		(property "Value" ""
			(at 0 0 90)
			(layer "F.Fab")
			(effects
				(font
					(size 1.27 1.27)
				)
			)
		)
		(duplicate_pad_numbers_are_jumpers no)
		(fp_poly
			(pts
				(xy 0.3048 -0.1016) (xy 0.3048 0.9906) (xy -0.3048 0.9906) (xy -0.3048 -0.1016)
			)
			(stroke
				(width 0)
				(type default)
			)
			(fill no)
			(layer "F.CrtYd")
		)
		(fp_line
			(start 0.3048 -0.1016)
			(end -0.3048 -0.1016)
			(stroke
				(width 0.1)
				(type default)
			)
			(layer "F.Fab")
		)
		(fp_line
			(start -0.3048 -0.1016)
			(end -0.3048 0.9906)
			(stroke
				(width 0.1)
				(type default)
			)
			(layer "F.Fab")
		)
		(fp_line
			(start 0.3048 0.9906)
			(end 0.3048 -0.1016)
			(stroke
				(width 0.1)
				(type default)
			)
			(layer "F.Fab")
		)
		(fp_line
			(start -0.3048 0.9906)
			(end 0.3048 0.9906)
			(stroke
				(width 0.1)
				(type default)
			)
			(layer "F.Fab")
		)
		(pad "1" smd rect
			(at 0 0 90)
			(size 0.508 0.508)
			(layers "F.Cu" "F.Mask" "F.Paste")
			(net "P3E_CPU0_PE1_PCH_TXN<13>")
		)
		(pad "2" smd rect
			(at 0 0.889 90)
			(size 0.508 0.508)
			(layers "F.Cu" "F.Mask" "F.Paste")
			(net "P3E_CPU0_PE1_PCH_C_TXN<13>")
		)
		(zone
			(layer "F.Cu")
			(hatch none 0.5)
			(connect_pads
				(clearance 0)
			)
			(min_thickness 0.25)
			(keepout
				(tracks allowed)
				(vias not_allowed)
				(pads allowed)
				(copperpour not_allowed)
				(footprints allowed)
			)
			(placement
				(enabled no)
				(sheetname "")
			)
			(fill
				(thermal_gap 0.5)
				(thermal_bridge_width 0.5)
				(island_removal_mode 0)
			)
			(polygon
				(pts
					(xy 324.8025 -121.412) (xy 324.8025 -121.92) (xy 325.1835 -121.92) (xy 325.1835 -121.412)
				)
			)
		)
	)
)
